(kicad_pcb
	(version 20260206)
	(generator "pcbnew")
	(generator_version "10.0")
	(general
		(thickness 1.6)
		(legacy_teardrops no)
	)
	(paper "A4")
	(title_block
		(title "01162023_DA0F0TEBIF0_F0T_Expander_BD_F_brd_V02_OCP.brd")
		(comment 1 "Grand Teton / footprints 4344-4349 of 9728")
	)
	(layers
		(0 "F.Cu" signal "TOP")
		(4 "In1.Cu" signal "GND")
		(6 "In2.Cu" signal "VCC")
		(8 "In3.Cu" signal "VCC1")
		(10 "In4.Cu" signal "GND1")
		(12 "In5.Cu" signal "IN1")
		(14 "In6.Cu" signal "GND2")
		(16 "In7.Cu" signal "IN2")
		(18 "In8.Cu" signal "GND3")
		(20 "In9.Cu" signal "IN3")
		(22 "In10.Cu" signal "GND4")
		(24 "In11.Cu" signal "IN4")
		(26 "In12.Cu" signal "GND5")
		(28 "In13.Cu" signal "IN5")
		(30 "In14.Cu" signal "GND6")
		(32 "In15.Cu" signal "IN6")
		(34 "In16.Cu" signal "GND7")
		(2 "B.Cu" signal "BOTTOM")
		(9 "F.Adhes" user "F.Adhesive")
		(11 "B.Adhes" user "B.Adhesive")
		(13 "F.Paste" user "Package Geometry/Pastemask Top")
		(15 "B.Paste" user "Package Geometry/Pastemask Bottom")
		(5 "F.SilkS" user "Ref Des/Silkscreen Top")
		(7 "B.SilkS" user "Ref Des/Silkscreen Bottom")
		(1 "F.Mask" user "Board Geometry/Soldermask Top")
		(3 "B.Mask" user "Board Geometry/Soldermask Bottom")
		(17 "Dwgs.User" user "User.Drawings")
		(19 "Cmts.User" user "User.Comments")
		(21 "Eco1.User" user "User.Eco1")
		(23 "Eco2.User" user "User.Eco2")
		(25 "Edge.Cuts" user "Board Geometry/Outline")
		(27 "Margin" user)
		(31 "F.CrtYd" user "Package Geometry/Place Bound Top")
		(29 "B.CrtYd" user "Package Geometry/Place Bound Bottom")
		(35 "F.Fab" user "Ref Des/Assembly Top")
		(33 "B.Fab" user "Ref Des/Assembly Bottom")
	)
	(footprint ""
		(layer "F.Cu")
		(at 278.987504 -395.162532 90)
		(property "Reference" "R1804"
			(at 0 0 90)
			(layer "F.SilkS")
			(hide yes)
			(effects
				(font
					(size 1.27 1.27)
				)
			)
		)
		(property "Value" ""
			(at 0 0 90)
			(layer "F.Fab")
			(effects
				(font
					(size 1.27 1.27)
				)
			)
		)
		(duplicate_pad_numbers_are_jumpers no)
		(fp_line
			(start 0.7874 -0.4064)
			(end 0.7874 0.4064)
			(stroke
				(width 0.1524)
				(type default)
			)
			(layer "F.SilkS")
		)
		(fp_line
			(start -0.7874 -0.4064)
			(end 0.7874 -0.4064)
			(stroke
				(width 0.1524)
				(type default)
			)
			(layer "F.SilkS")
		)
		(fp_line
			(start 0.7874 0.4064)
			(end -0.7874 0.4064)
			(stroke
				(width 0.1524)
				(type default)
			)
			(layer "F.SilkS")
		)
		(fp_line
			(start -0.7874 0.4064)
			(end -0.7874 -0.4064)
			(stroke
				(width 0.1524)
				(type default)
			)
			(layer "F.SilkS")
		)
		(fp_line
			(start -0.12065 -0.305054)
			(end -0.12065 -0.2794)
			(stroke
				(width 0.1)
				(type default)
			)
			(layer "F.Fab")
		)
		(fp_line
			(start -0.67945 -0.305054)
			(end -0.12065 -0.305054)
			(stroke
				(width 0.1)
				(type default)
			)
			(layer "F.Fab")
		)
		(fp_line
			(start 0.67945 -0.3048)
			(end 0.67945 0.3048)
			(stroke
				(width 0.1)
				(type default)
			)
			(layer "F.Fab")
		)
		(fp_line
			(start 0.12065 -0.3048)
			(end 0.67945 -0.3048)
			(stroke
				(width 0.1)
				(type default)
			)
			(layer "F.Fab")
		)
		(fp_line
			(start 0.12065 -0.2794)
			(end 0.12065 -0.3048)
			(stroke
				(width 0.1)
				(type default)
			)
			(layer "F.Fab")
		)
		(fp_line
			(start -0.12065 -0.2794)
			(end 0.12065 -0.2794)
			(stroke
				(width 0.1)
				(type default)
			)
			(layer "F.Fab")
		)
		(fp_line
			(start 0.120396 0.2794)
			(end -0.12065 0.2794)
			(stroke
				(width 0.1)
				(type default)
			)
			(layer "F.Fab")
		)
		(fp_line
			(start -0.12065 0.2794)
			(end -0.12065 0.3048)
			(stroke
				(width 0.1)
				(type default)
			)
			(layer "F.Fab")
		)
		(fp_line
			(start 0.67945 0.3048)
			(end 0.120396 0.3048)
			(stroke
				(width 0.1)
				(type default)
			)
			(layer "F.Fab")
		)
		(fp_line
			(start 0.120396 0.3048)
			(end 0.120396 0.2794)
			(stroke
				(width 0.1)
				(type default)
			)
			(layer "F.Fab")
		)
		(fp_line
			(start -0.12065 0.3048)
			(end -0.67945 0.3048)
			(stroke
				(width 0.1)
				(type default)
			)
			(layer "F.Fab")
		)
		(fp_line
			(start -0.67945 0.3048)
			(end -0.67945 -0.305054)
			(stroke
				(width 0.1)
				(type default)
			)
			(layer "F.Fab")
		)
		(pad "1" smd circle
			(at -0.40005 0 90)
			(size 0 0)
			(layers "F.Cu" "F.Mask" "F.Paste")
			(net "P3V3_AUX")
		)
		(pad "2" smd circle
			(at 0.40005 0 90)
			(size 0 0)
			(layers "F.Cu" "F.Mask" "F.Paste")
			(net "RST_MB_BIC_N")
		)
	)
	(footprint ""
		(layer "F.Cu")
		(at 12.852908 -247.598184 -90)
		(property "Reference" "C4245"
			(at 0 0 270)
			(layer "F.SilkS")
			(hide yes)
			(effects
				(font
					(size 1.27 1.27)
				)
			)
		)
		(property "Value" ""
			(at 0 0 270)
			(layer "F.Fab")
			(effects
				(font
					(size 1.27 1.27)
				)
			)
		)
		(duplicate_pad_numbers_are_jumpers no)
		(fp_line
			(start -1.524 0.762)
			(end -1.524 -0.762)
			(stroke
				(width 0.1524)
				(type default)
			)
			(layer "F.SilkS")
		)
		(fp_line
			(start 1.524 0.762)
			(end -1.524 0.762)
			(stroke
				(width 0.1524)
				(type default)
			)
			(layer "F.SilkS")
		)
		(fp_line
			(start -1.524 -0.762)
			(end 1.524 -0.762)
			(stroke
				(width 0.1524)
				(type default)
			)
			(layer "F.SilkS")
		)
		(fp_line
			(start 1.524 -0.762)
			(end 1.524 0.762)
			(stroke
				(width 0.1524)
				(type default)
			)
			(layer "F.SilkS")
		)
		(fp_line
			(start -1.1049 0.724916)
			(end 1.1049 0.724916)
			(stroke
				(width 0.1)
				(type default)
			)
			(layer "F.Fab")
		)
		(fp_line
			(start 1.1049 0.724916)
			(end 1.1049 -0.724916)
			(stroke
				(width 0.1)
				(type default)
			)
			(layer "F.Fab")
		)
		(fp_line
			(start -1.1049 -0.724916)
			(end -1.1049 0.724916)
			(stroke
				(width 0.1)
				(type default)
			)
			(layer "F.Fab")
		)
		(fp_line
			(start 1.1049 -0.724916)
			(end -1.1049 -0.724916)
			(stroke
				(width 0.1)
				(type default)
			)
			(layer "F.Fab")
		)
		(pad "1" smd rect
			(at -0.889 0 90)
			(size 1.016 1.27)
			(layers "F.Cu" "F.Mask" "F.Paste")
			(net "P1V25_SERDES_VDDPLL_PEX0_C11")
		)
		(pad "2" smd rect
			(at 0.889 0 90)
			(size 1.016 1.27)
			(layers "F.Cu" "F.Mask" "F.Paste")
			(net "GND")
		)
		(zone
			(layer "F.Cu")
			(hatch none 0.5)
			(connect_pads
				(clearance 0)
			)
			(min_thickness 0.25)
			(keepout
				(tracks not_allowed)
				(vias allowed)
				(pads allowed)
				(copperpour not_allowed)
				(footprints allowed)
			)
			(placement
				(enabled no)
				(sheetname "")
			)
			(fill
				(thermal_gap 0.5)
				(thermal_bridge_width 0.5)
				(island_removal_mode 0)
			)
			(polygon
				(pts
					(xy 13.577824 -247.928384) (xy 12.127992 -247.928384) (xy 12.127992 -247.267984) (xy 13.577824 -247.267984)
				)
			)
		)
	)
	(footprint ""
		(layer "F.Cu")
		(at 239.935512 -231.416606 90)
		(property "Reference" "R4515"
			(at 0 0 90)
			(layer "F.SilkS")
			(hide yes)
			(effects
				(font
					(size 1.27 1.27)
				)
			)
		)
		(property "Value" ""
			(at 0 0 90)
			(layer "F.Fab")
			(effects
				(font
					(size 1.27 1.27)
				)
			)
		)
		(duplicate_pad_numbers_are_jumpers no)
		(fp_line
			(start 0.7874 -0.4064)
			(end 0.7874 0.4064)
			(stroke
				(width 0.1524)
				(type default)
			)
			(layer "F.SilkS")
		)
		(fp_line
			(start -0.7874 -0.4064)
			(end 0.7874 -0.4064)
			(stroke
				(width 0.1524)
				(type default)
			)
			(layer "F.SilkS")
		)
		(fp_line
			(start 0.7874 0.4064)
			(end -0.7874 0.4064)
			(stroke
				(width 0.1524)
				(type default)
			)
			(layer "F.SilkS")
		)
		(fp_line
			(start -0.7874 0.4064)
			(end -0.7874 -0.4064)
			(stroke
				(width 0.1524)
				(type default)
			)
			(layer "F.SilkS")
		)
		(fp_line
			(start -0.12065 -0.305054)
			(end -0.12065 -0.2794)
			(stroke
				(width 0.1)
				(type default)
			)
			(layer "F.Fab")
		)
		(fp_line
			(start -0.67945 -0.305054)
			(end -0.12065 -0.305054)
			(stroke
				(width 0.1)
				(type default)
			)
			(layer "F.Fab")
		)
		(fp_line
			(start 0.67945 -0.3048)
			(end 0.67945 0.3048)
			(stroke
				(width 0.1)
				(type default)
			)
			(layer "F.Fab")
		)
		(fp_line
			(start 0.12065 -0.3048)
			(end 0.67945 -0.3048)
			(stroke
				(width 0.1)
				(type default)
			)
			(layer "F.Fab")
		)
		(fp_line
			(start 0.12065 -0.2794)
			(end 0.12065 -0.3048)
			(stroke
				(width 0.1)
				(type default)
			)
			(layer "F.Fab")
		)
		(fp_line
			(start -0.12065 -0.2794)
			(end 0.12065 -0.2794)
			(stroke
				(width 0.1)
				(type default)
			)
			(layer "F.Fab")
		)
		(fp_line
			(start 0.120396 0.2794)
			(end -0.12065 0.2794)
			(stroke
				(width 0.1)
				(type default)
			)
			(layer "F.Fab")
		)
		(fp_line
			(start -0.12065 0.2794)
			(end -0.12065 0.3048)
			(stroke
				(width 0.1)
				(type default)
			)
			(layer "F.Fab")
		)
		(fp_line
			(start 0.67945 0.3048)
			(end 0.120396 0.3048)
			(stroke
				(width 0.1)
				(type default)
			)
			(layer "F.Fab")
		)
		(fp_line
			(start 0.120396 0.3048)
			(end 0.120396 0.2794)
			(stroke
				(width 0.1)
				(type default)
			)
			(layer "F.Fab")
		)
		(fp_line
			(start -0.12065 0.3048)
			(end -0.67945 0.3048)
			(stroke
				(width 0.1)
				(type default)
			)
			(layer "F.Fab")
		)
		(fp_line
			(start -0.67945 0.3048)
			(end -0.67945 -0.305054)
			(stroke
				(width 0.1)
				(type default)
			)
			(layer "F.Fab")
		)
		(pad "1" smd circle
			(at -0.40005 0 90)
			(size 0 0)
			(layers "F.Cu" "F.Mask" "F.Paste")
			(net "SSD1_PWRDIS_BIC")
		)
		(pad "2" smd circle
			(at 0.40005 0 90)
			(size 0 0)
			(layers "F.Cu" "F.Mask" "F.Paste")
			(net "SSD1_PWRDIS_BIC_R")
		)
	)
	(footprint ""
		(layer "F.Cu")
		(at 60.070492 -375.19356 90)
		(property "Reference" "C4033"
			(at 0 0 90)
			(layer "F.SilkS")
			(hide yes)
			(effects
				(font
					(size 1.27 1.27)
				)
			)
		)
		(property "Value" ""
			(at 0 0 90)
			(layer "F.Fab")
			(effects
				(font
					(size 1.27 1.27)
				)
			)
		)
		(duplicate_pad_numbers_are_jumpers no)
		(fp_line
			(start 0.7874 -0.4064)
			(end 0.7874 0.4064)
			(stroke
				(width 0.1524)
				(type default)
			)
			(layer "F.SilkS")
		)
		(fp_line
			(start -0.7874 -0.4064)
			(end 0.7874 -0.4064)
			(stroke
				(width 0.1524)
				(type default)
			)
			(layer "F.SilkS")
		)
		(fp_line
			(start 0.7874 0.4064)
			(end -0.7874 0.4064)
			(stroke
				(width 0.1524)
				(type default)
			)
			(layer "F.SilkS")
		)
		(fp_line
			(start -0.7874 0.4064)
			(end -0.7874 -0.4064)
			(stroke
				(width 0.1524)
				(type default)
			)
			(layer "F.SilkS")
		)
		(fp_line
			(start -0.12065 -0.305054)
			(end -0.12065 -0.2794)
			(stroke
				(width 0.1)
				(type default)
			)
			(layer "F.Fab")
		)
		(fp_line
			(start -0.67945 -0.305054)
			(end -0.12065 -0.305054)
			(stroke
				(width 0.1)
				(type default)
			)
			(layer "F.Fab")
		)
		(fp_line
			(start 0.67945 -0.3048)
			(end 0.67945 0.3048)
			(stroke
				(width 0.1)
				(type default)
			)
			(layer "F.Fab")
		)
		(fp_line
			(start 0.12065 -0.3048)
			(end 0.67945 -0.3048)
			(stroke
				(width 0.1)
				(type default)
			)
			(layer "F.Fab")
		)
		(fp_line
			(start 0.12065 -0.2794)
			(end 0.12065 -0.3048)
			(stroke
				(width 0.1)
				(type default)
			)
			(layer "F.Fab")
		)
		(fp_line
			(start -0.12065 -0.2794)
			(end 0.12065 -0.2794)
			(stroke
				(width 0.1)
				(type default)
			)
			(layer "F.Fab")
		)
		(fp_line
			(start 0.120396 0.2794)
			(end -0.12065 0.2794)
			(stroke
				(width 0.1)
				(type default)
			)
			(layer "F.Fab")
		)
		(fp_line
			(start -0.12065 0.2794)
			(end -0.12065 0.3048)
			(stroke
				(width 0.1)
				(type default)
			)
			(layer "F.Fab")
		)
		(fp_line
			(start 0.67945 0.3048)
			(end 0.120396 0.3048)
			(stroke
				(width 0.1)
				(type default)
			)
			(layer "F.Fab")
		)
		(fp_line
			(start 0.120396 0.3048)
			(end 0.120396 0.2794)
			(stroke
				(width 0.1)
				(type default)
			)
			(layer "F.Fab")
		)
		(fp_line
			(start -0.12065 0.3048)
			(end -0.67945 0.3048)
			(stroke
				(width 0.1)
				(type default)
			)
			(layer "F.Fab")
		)
		(fp_line
			(start -0.67945 0.3048)
			(end -0.67945 -0.305054)
			(stroke
				(width 0.1)
				(type default)
			)
			(layer "F.Fab")
		)
		(pad "1" smd circle
			(at -0.40005 0 90)
			(size 0 0)
			(layers "F.Cu" "F.Mask" "F.Paste")
			(net "GND")
		)
		(pad "2" smd circle
			(at 0.40005 0 90)
			(size 0 0)
			(layers "F.Cu" "F.Mask" "F.Paste")
			(net "GPU_BASE_PWR_EN")
		)
	)
	(footprint ""
		(layer "F.Cu")
		(at 400.543776 -46.90491)
		(property "Reference" "R653"
			(at 0 0 0)
			(layer "F.SilkS")
			(hide yes)
			(effects
				(font
					(size 1.27 1.27)
				)
			)
		)
		(property "Value" ""
			(at 0 0 0)
			(layer "F.Fab")
			(effects
				(font
					(size 1.27 1.27)
				)
			)
		)
		(duplicate_pad_numbers_are_jumpers no)
		(fp_line
			(start -0.7874 -0.4064)
			(end 0.7874 -0.4064)
			(stroke
				(width 0.1524)
				(type default)
			)
			(layer "F.SilkS")
		)
		(fp_line
			(start -0.7874 0.4064)
			(end -0.7874 -0.4064)
			(stroke
				(width 0.1524)
				(type default)
			)
			(layer "F.SilkS")
		)
		(fp_line
			(start 0.7874 -0.4064)
			(end 0.7874 0.4064)
			(stroke
				(width 0.1524)
				(type default)
			)
			(layer "F.SilkS")
		)
		(fp_line
			(start 0.7874 0.4064)
			(end -0.7874 0.4064)
			(stroke
				(width 0.1524)
				(type default)
			)
			(layer "F.SilkS")
		)
		(fp_line
			(start -0.67945 -0.305054)
			(end -0.12065 -0.305054)
			(stroke
				(width 0.1)
				(type default)
			)
			(layer "F.Fab")
		)
		(fp_line
			(start -0.67945 0.3048)
			(end -0.67945 -0.305054)
			(stroke
				(width 0.1)
				(type default)
			)
			(layer "F.Fab")
		)
		(fp_line
			(start -0.12065 -0.305054)
			(end -0.12065 -0.2794)
			(stroke
				(width 0.1)
				(type default)
			)
			(layer "F.Fab")
		)
		(fp_line
			(start -0.12065 -0.2794)
			(end 0.12065 -0.2794)
			(stroke
				(width 0.1)
				(type default)
			)
			(layer "F.Fab")
		)
		(fp_line
			(start -0.12065 0.2794)
			(end -0.12065 0.3048)
			(stroke
				(width 0.1)
				(type default)
			)
			(layer "F.Fab")
		)
		(fp_line
			(start -0.12065 0.3048)
			(end -0.67945 0.3048)
			(stroke
				(width 0.1)
				(type default)
			)
			(layer "F.Fab")
		)
		(fp_line
			(start 0.120396 0.2794)
			(end -0.12065 0.2794)
			(stroke
				(width 0.1)
				(type default)
			)
			(layer "F.Fab")
		)
		(fp_line
			(start 0.120396 0.3048)
			(end 0.120396 0.2794)
			(stroke
				(width 0.1)
				(type default)
			)
			(layer "F.Fab")
		)
		(fp_line
			(start 0.12065 -0.3048)
			(end 0.67945 -0.3048)
			(stroke
				(width 0.1)
				(type default)
			)
			(layer "F.Fab")
		)
		(fp_line
			(start 0.12065 -0.2794)
			(end 0.12065 -0.3048)
			(stroke
				(width 0.1)
				(type default)
			)
			(layer "F.Fab")
		)
		(fp_line
			(start 0.67945 -0.3048)
			(end 0.67945 0.3048)
			(stroke
				(width 0.1)
				(type default)
			)
			(layer "F.Fab")
		)
		(fp_line
			(start 0.67945 0.3048)
			(end 0.120396 0.3048)
			(stroke
				(width 0.1)
				(type default)
			)
			(layer "F.Fab")
		)
		(pad "1" smd circle
			(at -0.40005 0)
			(size 0 0)
			(layers "F.Cu" "F.Mask" "F.Paste")
			(net "SSD13_ADC_ALERT_N")
		)
		(pad "2" smd circle
			(at 0.40005 0)
			(size 0 0)
			(layers "F.Cu" "F.Mask" "F.Paste")
			(net "SSD_8_15_ADC_ALERT_N")
		)
	)
	(footprint ""
		(layer "F.Cu")
		(at 237.903512 -234.728004 -90)
		(property "Reference" "R6187"
			(at 0 0 270)
			(layer "F.SilkS")
			(hide yes)
			(effects
				(font
					(size 1.27 1.27)
				)
			)
		)
		(property "Value" ""
			(at 0 0 270)
			(layer "F.Fab")
			(effects
				(font
					(size 1.27 1.27)
				)
			)
		)
		(duplicate_pad_numbers_are_jumpers no)
		(fp_line
			(start -0.7874 0.4064)
			(end -0.7874 -0.4064)
			(stroke
				(width 0.1524)
				(type default)
			)
			(layer "F.SilkS")
		)
		(fp_line
			(start 0.7874 0.4064)
			(end -0.7874 0.4064)
			(stroke
				(width 0.1524)
				(type default)
			)
			(layer "F.SilkS")
		)
		(fp_line
			(start -0.7874 -0.4064)
			(end 0.7874 -0.4064)
			(stroke
				(width 0.1524)
				(type default)
			)
			(layer "F.SilkS")
		)
		(fp_line
			(start 0.7874 -0.4064)
			(end 0.7874 0.4064)
			(stroke
				(width 0.1524)
				(type default)
			)
			(layer "F.SilkS")
		)
		(fp_line
			(start -0.67945 0.3048)
			(end -0.67945 -0.305054)
			(stroke
				(width 0.1)
				(type default)
			)
			(layer "F.Fab")
		)
		(fp_line
			(start -0.12065 0.3048)
			(end -0.67945 0.3048)
			(stroke
				(width 0.1)
				(type default)
			)
			(layer "F.Fab")
		)
		(fp_line
			(start 0.120396 0.3048)
			(end 0.120396 0.2794)
			(stroke
				(width 0.1)
				(type default)
			)
			(layer "F.Fab")
		)
		(fp_line
			(start 0.67945 0.3048)
			(end 0.120396 0.3048)
			(stroke
				(width 0.1)
				(type default)
			)
			(layer "F.Fab")
		)
		(fp_line
			(start -0.12065 0.2794)
			(end -0.12065 0.3048)
			(stroke
				(width 0.1)
				(type default)
			)
			(layer "F.Fab")
		)
		(fp_line
			(start 0.120396 0.2794)
			(end -0.12065 0.2794)
			(stroke
				(width 0.1)
				(type default)
			)
			(layer "F.Fab")
		)
		(fp_line
			(start -0.12065 -0.2794)
			(end 0.12065 -0.2794)
			(stroke
				(width 0.1)
				(type default)
			)
			(layer "F.Fab")
		)
		(fp_line
			(start 0.12065 -0.2794)
			(end 0.12065 -0.3048)
			(stroke
				(width 0.1)
				(type default)
			)
			(layer "F.Fab")
		)
		(fp_line
			(start 0.12065 -0.3048)
			(end 0.67945 -0.3048)
			(stroke
				(width 0.1)
				(type default)
			)
			(layer "F.Fab")
		)
		(fp_line
			(start 0.67945 -0.3048)
			(end 0.67945 0.3048)
			(stroke
				(width 0.1)
				(type default)
			)
			(layer "F.Fab")
		)
		(fp_line
			(start -0.67945 -0.305054)
			(end -0.12065 -0.305054)
			(stroke
				(width 0.1)
				(type default)
			)
			(layer "F.Fab")
		)
		(fp_line
			(start -0.12065 -0.305054)
			(end -0.12065 -0.2794)
			(stroke
				(width 0.1)
				(type default)
			)
			(layer "F.Fab")
		)
		(pad "1" smd circle
			(at -0.40005 0 270)
			(size 0 0)
			(layers "F.Cu" "F.Mask" "F.Paste")
			(net "GND")
		)
		(pad "2" smd circle
			(at 0.40005 0 270)
			(size 0 0)
			(layers "F.Cu" "F.Mask" "F.Paste")
			(net "SSD5_PWRDIS_BIC_R")
		)
	)
)
